# BASEBOARD_FAB2 (Tioga Pass) — schematic netlist excerpt (pin names and nets, part order shuffled) for the footprints in the layout excerpt that follows; sources: Cadence DE-HDL packaged netlist, KiCad conversion of Wiwynn_Tioga_Pass_MB.brd

R4E19  RES  68.1K 1% EMPTY  pkg 0402  page 202 : A = VR_PVCCIN_CPU0_PH2_OCSET ; B = GND
FB25W2  BLM15AG121SN-1GP  pkg DISCRET-G  page 254 : \1\ = XDP_PCH_TCK1_R ; \2\ = XDP_PCH_TCK1
R5P1  RES  100.0K 1% CHIP  pkg 0603  page 37 : A = PVCCIN_CPU0 ; B = VSENSE_VCCINR2PMAX_CPU0

(kicad_pcb
	(version 20260206)
	(generator "pcbnew")
	(generator_version "10.0")
	(general
		(thickness 1.6)
		(legacy_teardrops no)
	)
	(paper "A4")
	(title_block
		(title "Wiwynn_Tioga_Pass_MB.brd")
		(comment 1 "Tioga Pass / footprints 517-519 of 4770")
	)
	(layers
		(0 "F.Cu" signal "TOP")
		(4 "In1.Cu" signal "L2GND")
		(6 "In2.Cu" signal "L3")
		(8 "In3.Cu" signal "L4GND")
		(10 "In4.Cu" signal "L5")
		(12 "In5.Cu" signal "L6GND")
		(14 "In6.Cu" signal "L7VCC")
		(16 "In7.Cu" signal "L8VCC")
		(18 "In8.Cu" signal "L9GND")
		(20 "In9.Cu" signal "L10")
		(22 "In10.Cu" signal "L11GND")
		(24 "In11.Cu" signal "L12")
		(26 "In12.Cu" signal "L13GND")
		(2 "B.Cu" signal "BOTTOM")
		(9 "F.Adhes" user "F.Adhesive")
		(11 "B.Adhes" user "B.Adhesive")
		(13 "F.Paste" user "Package Geometry/Pastemask Top")
		(15 "B.Paste" user "Package Geometry/Pastemask Bottom")
		(5 "F.SilkS" user "Ref Des/Silkscreen Top")
		(7 "B.SilkS" user "Ref Des/Silkscreen Bottom")
		(1 "F.Mask" user "Board Geometry/Soldermask Top")
		(3 "B.Mask" user "Board Geometry/Soldermask Bottom")
		(17 "Dwgs.User" user "User.Drawings")
		(19 "Cmts.User" user "User.Comments")
		(21 "Eco1.User" user "User.Eco1")
		(23 "Eco2.User" user "User.Eco2")
		(25 "Edge.Cuts" user "Board Geometry/Outline")
		(27 "Margin" user)
		(31 "F.CrtYd" user "Package Geometry/Place Bound Top")
		(29 "B.CrtYd" user "Package Geometry/Place Bound Bottom")
		(35 "F.Fab" user "Ref Des/Assembly Top")
		(33 "B.Fab" user "Ref Des/Assembly Bottom")
	)
	(footprint ""
		(layer "F.Cu")
		(at 209.296 -51.382168)
		(property "Reference" "R5P1"
			(at 0 0 0)
			(layer "F.SilkS")
			(hide yes)
			(effects
				(font
					(size 1.27 1.27)
				)
			)
		)
		(property "Value" ""
			(at 0 0 0)
			(layer "F.Fab")
			(effects
				(font
					(size 1.27 1.27)
				)
			)
		)
		(duplicate_pad_numbers_are_jumpers no)
		(fp_poly
			(pts
				(xy -0.4953 -0.2032) (xy 0.4953 -0.2032) (xy 0.4953 1.6002) (xy -0.4953 1.6002)
			)
			(stroke
				(width 0)
				(type default)
			)
			(fill no)
			(layer "F.CrtYd")
		)
		(fp_line
			(start -0.4953 -0.2032)
			(end 0.4953 -0.2032)
			(stroke
				(width 0.1)
				(type default)
			)
			(layer "F.Fab")
		)
		(fp_line
			(start -0.4953 1.6002)
			(end -0.4953 -0.2032)
			(stroke
				(width 0.1)
				(type default)
			)
			(layer "F.Fab")
		)
		(fp_line
			(start 0.4953 -0.2032)
			(end 0.4953 1.6002)
			(stroke
				(width 0.1)
				(type default)
			)
			(layer "F.Fab")
		)
		(fp_line
			(start 0.4953 1.6002)
			(end -0.4953 1.6002)
			(stroke
				(width 0.1)
				(type default)
			)
			(layer "F.Fab")
		)
		(pad "1" smd rect
			(at 0 0)
			(size 0.762 0.889)
			(layers "F.Cu" "F.Mask" "F.Paste")
			(net "PVCCIN_CPU0")
		)
		(pad "2" smd rect
			(at 0 1.397)
			(size 0.762 0.889)
			(layers "F.Cu" "F.Mask" "F.Paste")
			(net "VSENSE_VCCINR2PMAX_CPU0")
		)
		(zone
			(layer "F.Cu")
			(hatch none 0.5)
			(connect_pads
				(clearance 0)
			)
			(min_thickness 0.25)
			(keepout
				(tracks not_allowed)
				(vias allowed)
				(pads allowed)
				(copperpour not_allowed)
				(footprints allowed)
			)
			(placement
				(enabled no)
				(sheetname "")
			)
			(fill
				(thermal_gap 0.5)
				(thermal_bridge_width 0.5)
				(island_removal_mode 0)
			)
			(polygon
				(pts
					(xy 208.915 -50.429668) (xy 209.677 -50.429668) (xy 209.677 -50.937668) (xy 208.915 -50.937668)
				)
			)
		)
		(zone
			(layer "F.Cu")
			(hatch none 0.5)
			(connect_pads
				(clearance 0)
			)
			(min_thickness 0.25)
			(keepout
				(tracks allowed)
				(vias not_allowed)
				(pads allowed)
				(copperpour not_allowed)
				(footprints allowed)
			)
			(placement
				(enabled no)
				(sheetname "")
			)
			(fill
				(thermal_gap 0.5)
				(thermal_bridge_width 0.5)
				(island_removal_mode 0)
			)
			(polygon
				(pts
					(xy 209.677 -50.429668) (xy 209.677 -50.937668) (xy 208.915 -50.937668) (xy 208.915 -50.429668)
				)
			)
		)
	)
	(footprint ""
		(layer "F.Cu")
		(at 439.160412 -153.572718 90)
		(property "Reference" "FB25W2"
			(at 0 0 90)
			(layer "F.SilkS")
			(hide yes)
			(effects
				(font
					(size 1.27 1.27)
				)
			)
		)
		(property "Value" "*"
			(at -0.0127 -7.01675 90)
			(unlocked yes)
			(layer "F.Fab")
			(hide yes)
			(effects
				(font
					(size 0.889 0.889)
					(thickness 0.1524)
				)
			)
		)
		(property "Device Type" "BLM15AG121SN-1GP_DISCRET-G-BLMA"
			(at -0.0127 -8.54075 90)
			(unlocked yes)
			(layer "F.Fab")
			(hide yes)
			(effects
				(font
					(size 0.889 0.889)
					(thickness 0.1524)
				)
			)
		)
		(duplicate_pad_numbers_are_jumpers no)
		(fp_line
			(start 0.508 -0.9398)
			(end -0.508 -0.9398)
			(stroke
				(width 0.1524)
				(type default)
			)
			(layer "F.SilkS")
		)
		(fp_line
			(start -0.508 -0.9398)
			(end -0.508 0.9398)
			(stroke
				(width 0.1524)
				(type default)
			)
			(layer "F.SilkS")
		)
		(fp_line
			(start -0.508 0.9398)
			(end -0.508 0.8636)
			(stroke
				(width 0.1524)
				(type default)
			)
			(layer "F.SilkS")
		)
		(fp_rect
			(start -0.508 0.9398)
			(end 0.508 -0.9398)
			(stroke
				(width 0)
				(type default)
			)
			(fill no)
			(layer "F.CrtYd")
		)
		(fp_rect
			(start -0.508 0.9398)
			(end 0.508 -0.9398)
			(stroke
				(width 0)
				(type default)
			)
			(fill no)
			(layer "F.Fab")
		)
		(pad "1" smd custom
			(at 0 -0.4445 90)
			(size 0.1397 0.1397)
			(layers "F.Cu" "F.Mask" "F.Paste")
			(net "XDP_PCH_TCK1_R")
			(options
				(clearance outline)
				(anchor circle)
			)
			(primitives
				(gr_poly
					(pts
						(arc
							(start -0.1778 -0.2794)
							(mid -0.249642 -0.249642)
							(end -0.2794 -0.1778)
						)
						(arc
							(start -0.2794 0.1778)
							(mid -0.249642 0.249642)
							(end -0.1778 0.2794)
						)
						(arc
							(start 0.1778 0.2794)
							(mid 0.249642 0.249642)
							(end 0.2794 0.1778)
						)
						(arc
							(start 0.2794 -0.1778)
							(mid 0.249642 -0.249642)
							(end 0.1778 -0.2794)
						)
					)
					(width 0)
					(fill yes)
				)
			)
		)
		(pad "2" smd custom
			(at 0 0.4445 90)
			(size 0.1397 0.1397)
			(layers "F.Cu" "F.Mask" "F.Paste")
			(net "XDP_PCH_TCK1")
			(options
				(clearance outline)
				(anchor circle)
			)
			(primitives
				(gr_poly
					(pts
						(arc
							(start -0.1778 -0.2794)
							(mid -0.249642 -0.249642)
							(end -0.2794 -0.1778)
						)
						(arc
							(start -0.2794 0.1778)
							(mid -0.249642 0.249642)
							(end -0.1778 0.2794)
						)
						(arc
							(start 0.1778 0.2794)
							(mid 0.249642 0.249642)
							(end 0.2794 0.1778)
						)
						(arc
							(start 0.2794 -0.1778)
							(mid 0.249642 -0.249642)
							(end 0.1778 -0.2794)
						)
					)
					(width 0)
					(fill yes)
				)
			)
		)
	)
	(footprint ""
		(layer "F.Cu")
		(at 193.4464 -63.25108)
		(property "Reference" "R4E19"
			(at 0 0 0)
			(layer "F.SilkS")
			(hide yes)
			(effects
				(font
					(size 1.27 1.27)
				)
			)
		)
		(property "Value" ""
			(at 0 0 0)
			(layer "F.Fab")
			(effects
				(font
					(size 1.27 1.27)
				)
			)
		)
		(duplicate_pad_numbers_are_jumpers no)
		(fp_poly
			(pts
				(xy -0.2794 -0.1016) (xy 0.2794 -0.1016) (xy 0.2794 0.9906) (xy -0.2794 0.9906)
			)
			(stroke
				(width 0)
				(type default)
			)
			(fill no)
			(layer "F.CrtYd")
		)
		(fp_line
			(start -0.2794 -0.1016)
			(end -0.2794 0.9906)
			(stroke
				(width 0.1)
				(type default)
			)
			(layer "F.Fab")
		)
		(fp_line
			(start -0.2794 0.9906)
			(end 0.2794 0.9906)
			(stroke
				(width 0.1)
				(type default)
			)
			(layer "F.Fab")
		)
		(fp_line
			(start 0.2794 -0.1016)
			(end -0.2794 -0.1016)
			(stroke
				(width 0.1)
				(type default)
			)
			(layer "F.Fab")
		)
		(fp_line
			(start 0.2794 0.9906)
			(end 0.2794 -0.1016)
			(stroke
				(width 0.1)
				(type default)
			)
			(layer "F.Fab")
		)
		(pad "1" smd rect
			(at 0 0)
			(size 0.508 0.508)
			(layers "F.Cu" "F.Mask" "F.Paste")
			(net "VR_PVCCIN_CPU0_PH2_OCSET")
		)
		(pad "2" smd rect
			(at 0 0.889)
			(size 0.508 0.508)
			(layers "F.Cu" "F.Mask" "F.Paste")
			(net "GND")
		)
		(zone
			(layer "F.Cu")
			(hatch none 0.5)
			(connect_pads
				(clearance 0)
			)
			(min_thickness 0.25)
			(keepout
				(tracks allowed)
				(vias not_allowed)
				(pads allowed)
				(copperpour not_allowed)
				(footprints allowed)
			)
			(placement
				(enabled no)
				(sheetname "")
			)
			(fill
				(thermal_gap 0.5)
				(thermal_bridge_width 0.5)
				(island_removal_mode 0)
			)
			(polygon
				(pts
					(xy 193.1924 -62.99708) (xy 193.7004 -62.99708) (xy 193.7004 -62.61608) (xy 193.1924 -62.61608)
				)
			)
		)
		(zone
			(layer "F.Cu")
			(hatch none 0.5)
			(connect_pads
				(clearance 0)
			)
			(min_thickness 0.25)
			(keepout
				(tracks not_allowed)
				(vias allowed)
				(pads allowed)
				(copperpour not_allowed)
				(footprints allowed)
			)
			(placement
				(enabled no)
				(sheetname "")
			)
			(fill
				(thermal_gap 0.5)
				(thermal_bridge_width 0.5)
				(island_removal_mode 0)
			)
			(polygon
				(pts
					(xy 193.1924 -62.61608) (xy 193.7004 -62.61608) (xy 193.7004 -62.99708) (xy 193.1924 -62.99708)
				)
			)
		)
	)
)
